# S9S_MB_2U (Grand Teton) — schematic netlist excerpt (pin names and nets, part order shuffled) for the footprints in the layout excerpt that follows; sources: Cadence DE-HDL packaged netlist, KiCad conversion of 03242023_DA0F0TMBIJ0_F0T_Motherboard_J_brd_V01_OCP.brd

R2530  Q_RES  4.7K 5% CHIP  pkg 0402LF  page 247 : A = P12V_AUX ; B = P12V_AUX_BLEEDING
C407  Q_CAP  22UF 4V 20% X6S  pkg C0402  page 74 : A = PVCCFA_EHV_FIVRA_CPU0 ; B = GND

(kicad_pcb
	(version 20260206)
	(generator "pcbnew")
	(generator_version "10.0")
	(general
		(thickness 1.6)
		(legacy_teardrops no)
	)
	(paper "A4")
	(title_block
		(title "03242023_DA0F0TMBIJ0_F0T_Motherboard_J_brd_V01_OCP.brd")
		(comment 1 "Grand Teton / footprints 3045-3046 of 6105")
	)
	(layers
		(0 "F.Cu" signal "TOP")
		(4 "In1.Cu" signal "GND")
		(6 "In2.Cu" signal "IN1")
		(8 "In3.Cu" signal "GND1")
		(10 "In4.Cu" signal "IN2")
		(12 "In5.Cu" signal "GND2")
		(14 "In6.Cu" signal "IN3")
		(16 "In7.Cu" signal "GND3")
		(18 "In8.Cu" signal "VCC")
		(20 "In9.Cu" signal "VCC1")
		(22 "In10.Cu" signal "GND4")
		(24 "In11.Cu" signal "IN4")
		(26 "In12.Cu" signal "GND5")
		(28 "In13.Cu" signal "IN5")
		(30 "In14.Cu" signal "GND6")
		(32 "In15.Cu" signal "IN6")
		(34 "In16.Cu" signal "GND7")
		(2 "B.Cu" signal "BOTTOM")
		(9 "F.Adhes" user "F.Adhesive")
		(11 "B.Adhes" user "B.Adhesive")
		(13 "F.Paste" user "Package Geometry/Pastemask Top")
		(15 "B.Paste" user "Package Geometry/Pastemask Bottom")
		(5 "F.SilkS" user "Ref Des/Silkscreen Top")
		(7 "B.SilkS" user "Ref Des/Silkscreen Bottom")
		(1 "F.Mask" user "Board Geometry/Soldermask Top")
		(3 "B.Mask" user "Board Geometry/Soldermask Bottom")
		(17 "Dwgs.User" user "User.Drawings")
		(19 "Cmts.User" user "User.Comments")
		(21 "Eco1.User" user "User.Eco1")
		(23 "Eco2.User" user "User.Eco2")
		(25 "Edge.Cuts" user "Board Geometry/Outline")
		(27 "Margin" user)
		(31 "F.CrtYd" user "Package Geometry/Place Bound Top")
		(29 "B.CrtYd" user "Package Geometry/Place Bound Bottom")
		(35 "F.Fab" user "Ref Des/Assembly Top")
		(33 "B.Fab" user "Ref Des/Assembly Bottom")
	)
	(footprint ""
		(layer "F.Cu")
		(at 364.50143 -260.364986 -90)
		(property "Reference" "C407"
			(at 0 0 270)
			(layer "F.SilkS")
			(hide yes)
			(effects
				(font
					(size 1.27 1.27)
				)
			)
		)
		(property "Value" ""
			(at 0 0 270)
			(layer "F.Fab")
			(effects
				(font
					(size 1.27 1.27)
				)
			)
		)
		(duplicate_pad_numbers_are_jumpers no)
		(fp_line
			(start -0.7874 0.4064)
			(end -0.7874 -0.4064)
			(stroke
				(width 0.1524)
				(type default)
			)
			(layer "F.SilkS")
		)
		(fp_line
			(start 0.7874 0.4064)
			(end -0.7874 0.4064)
			(stroke
				(width 0.1524)
				(type default)
			)
			(layer "F.SilkS")
		)
		(fp_line
			(start -0.7874 -0.4064)
			(end 0.7874 -0.4064)
			(stroke
				(width 0.1524)
				(type default)
			)
			(layer "F.SilkS")
		)
		(fp_line
			(start 0.7874 -0.4064)
			(end 0.7874 0.4064)
			(stroke
				(width 0.1524)
				(type default)
			)
			(layer "F.SilkS")
		)
		(fp_line
			(start -0.67945 0.3048)
			(end -0.67945 -0.305054)
			(stroke
				(width 0.1)
				(type default)
			)
			(layer "F.Fab")
		)
		(fp_line
			(start -0.12065 0.3048)
			(end -0.67945 0.3048)
			(stroke
				(width 0.1)
				(type default)
			)
			(layer "F.Fab")
		)
		(fp_line
			(start 0.120396 0.3048)
			(end 0.120396 0.2794)
			(stroke
				(width 0.1)
				(type default)
			)
			(layer "F.Fab")
		)
		(fp_line
			(start 0.67945 0.3048)
			(end 0.120396 0.3048)
			(stroke
				(width 0.1)
				(type default)
			)
			(layer "F.Fab")
		)
		(fp_line
			(start -0.12065 0.2794)
			(end -0.12065 0.3048)
			(stroke
				(width 0.1)
				(type default)
			)
			(layer "F.Fab")
		)
		(fp_line
			(start 0.120396 0.2794)
			(end -0.12065 0.2794)
			(stroke
				(width 0.1)
				(type default)
			)
			(layer "F.Fab")
		)
		(fp_line
			(start -0.12065 -0.2794)
			(end 0.12065 -0.2794)
			(stroke
				(width 0.1)
				(type default)
			)
			(layer "F.Fab")
		)
		(fp_line
			(start 0.12065 -0.2794)
			(end 0.12065 -0.3048)
			(stroke
				(width 0.1)
				(type default)
			)
			(layer "F.Fab")
		)
		(fp_line
			(start 0.12065 -0.3048)
			(end 0.67945 -0.3048)
			(stroke
				(width 0.1)
				(type default)
			)
			(layer "F.Fab")
		)
		(fp_line
			(start 0.67945 -0.3048)
			(end 0.67945 0.3048)
			(stroke
				(width 0.1)
				(type default)
			)
			(layer "F.Fab")
		)
		(fp_line
			(start -0.67945 -0.305054)
			(end -0.12065 -0.305054)
			(stroke
				(width 0.1)
				(type default)
			)
			(layer "F.Fab")
		)
		(fp_line
			(start -0.12065 -0.305054)
			(end -0.12065 -0.2794)
			(stroke
				(width 0.1)
				(type default)
			)
			(layer "F.Fab")
		)
		(pad "1" smd circle
			(at -0.40005 0 270)
			(size 0 0)
			(layers "F.Cu" "F.Mask" "F.Paste")
			(net "PVCCFA_EHV_FIVRA_CPU0")
		)
		(pad "2" smd circle
			(at 0.40005 0 270)
			(size 0 0)
			(layers "F.Cu" "F.Mask" "F.Paste")
			(net "GND")
		)
	)
	(footprint ""
		(layer "F.Cu")
		(at 206.45374 -131.669028 90)
		(property "Reference" "R2530"
			(at 0 0 90)
			(layer "F.SilkS")
			(hide yes)
			(effects
				(font
					(size 1.27 1.27)
				)
			)
		)
		(property "Value" ""
			(at 0 0 90)
			(layer "F.Fab")
			(effects
				(font
					(size 1.27 1.27)
				)
			)
		)
		(duplicate_pad_numbers_are_jumpers no)
		(fp_line
			(start 0.7874 -0.4064)
			(end 0.7874 0.4064)
			(stroke
				(width 0.1524)
				(type default)
			)
			(layer "F.SilkS")
		)
		(fp_line
			(start -0.7874 -0.4064)
			(end 0.7874 -0.4064)
			(stroke
				(width 0.1524)
				(type default)
			)
			(layer "F.SilkS")
		)
		(fp_line
			(start 0.7874 0.4064)
			(end -0.7874 0.4064)
			(stroke
				(width 0.1524)
				(type default)
			)
			(layer "F.SilkS")
		)
		(fp_line
			(start -0.7874 0.4064)
			(end -0.7874 -0.4064)
			(stroke
				(width 0.1524)
				(type default)
			)
			(layer "F.SilkS")
		)
		(fp_line
			(start -0.12065 -0.305054)
			(end -0.12065 -0.2794)
			(stroke
				(width 0.1)
				(type default)
			)
			(layer "F.Fab")
		)
		(fp_line
			(start -0.67945 -0.305054)
			(end -0.12065 -0.305054)
			(stroke
				(width 0.1)
				(type default)
			)
			(layer "F.Fab")
		)
		(fp_line
			(start 0.67945 -0.3048)
			(end 0.67945 0.3048)
			(stroke
				(width 0.1)
				(type default)
			)
			(layer "F.Fab")
		)
		(fp_line
			(start 0.12065 -0.3048)
			(end 0.67945 -0.3048)
			(stroke
				(width 0.1)
				(type default)
			)
			(layer "F.Fab")
		)
		(fp_line
			(start 0.12065 -0.2794)
			(end 0.12065 -0.3048)
			(stroke
				(width 0.1)
				(type default)
			)
			(layer "F.Fab")
		)
		(fp_line
			(start -0.12065 -0.2794)
			(end 0.12065 -0.2794)
			(stroke
				(width 0.1)
				(type default)
			)
			(layer "F.Fab")
		)
		(fp_line
			(start 0.120396 0.2794)
			(end -0.12065 0.2794)
			(stroke
				(width 0.1)
				(type default)
			)
			(layer "F.Fab")
		)
		(fp_line
			(start -0.12065 0.2794)
			(end -0.12065 0.3048)
			(stroke
				(width 0.1)
				(type default)
			)
			(layer "F.Fab")
		)
		(fp_line
			(start 0.67945 0.3048)
			(end 0.120396 0.3048)
			(stroke
				(width 0.1)
				(type default)
			)
			(layer "F.Fab")
		)
		(fp_line
			(start 0.120396 0.3048)
			(end 0.120396 0.2794)
			(stroke
				(width 0.1)
				(type default)
			)
			(layer "F.Fab")
		)
		(fp_line
			(start -0.12065 0.3048)
			(end -0.67945 0.3048)
			(stroke
				(width 0.1)
				(type default)
			)
			(layer "F.Fab")
		)
		(fp_line
			(start -0.67945 0.3048)
			(end -0.67945 -0.305054)
			(stroke
				(width 0.1)
				(type default)
			)
			(layer "F.Fab")
		)
		(pad "1" smd circle
			(at -0.40005 0 90)
			(size 0 0)
			(layers "F.Cu" "F.Mask" "F.Paste")
			(net "P12V_AUX")
		)
		(pad "2" smd circle
			(at 0.40005 0 90)
			(size 0 0)
			(layers "F.Cu" "F.Mask" "F.Paste")
			(net "P12V_AUX_BLEEDING")
		)
	)
)
